(kicad_pcb
	(version 20260206)
	(generator "pcbnew")
	(generator_version "10.0")
	(general
		(thickness 1.6)
		(legacy_teardrops no)
	)
	(paper "A4")
	(title_block
		(title "12092022_DA0F0TMDCD0_F0T_Management_Board_D_brd_V3_OCP.brd")
		(comment 1 "Grand Teton / footprints 833-838 of 1440")
	)
	(layers
		(0 "F.Cu" signal "TOP")
		(4 "In1.Cu" signal "GND")
		(6 "In2.Cu" signal "IN1")
		(8 "In3.Cu" signal "GND1")
		(10 "In4.Cu" signal "IN2")
		(12 "In5.Cu" signal "VCC")
		(14 "In6.Cu" signal "VCC1")
		(16 "In7.Cu" signal "IN3")
		(18 "In8.Cu" signal "GND2")
		(20 "In9.Cu" signal "IN4")
		(22 "In10.Cu" signal "GND3")
		(2 "B.Cu" signal "BOTTOM")
		(9 "F.Adhes" user "F.Adhesive")
		(11 "B.Adhes" user "B.Adhesive")
		(13 "F.Paste" user "Package Geometry/Pastemask Top")
		(15 "B.Paste" user "Package Geometry/Pastemask Bottom")
		(5 "F.SilkS" user "Ref Des/Silkscreen Top")
		(7 "B.SilkS" user "Ref Des/Silkscreen Bottom")
		(1 "F.Mask" user "Board Geometry/Soldermask Top")
		(3 "B.Mask" user "Board Geometry/Soldermask Bottom")
		(17 "Dwgs.User" user "User.Drawings")
		(19 "Cmts.User" user "User.Comments")
		(21 "Eco1.User" user "User.Eco1")
		(23 "Eco2.User" user "User.Eco2")
		(25 "Edge.Cuts" user "Board Geometry/Outline")
		(27 "Margin" user)
		(31 "F.CrtYd" user "Package Geometry/Place Bound Top")
		(29 "B.CrtYd" user "Package Geometry/Place Bound Bottom")
		(35 "F.Fab" user "Ref Des/Assembly Top")
		(33 "B.Fab" user "Ref Des/Assembly Bottom")
	)
	(footprint ""
		(layer "B.Cu")
		(at 61.330586 -49.314354)
		(property "Reference" "C49"
			(at 0 0 0)
			(layer "B.SilkS")
			(hide yes)
			(effects
				(font
					(size 1.27 1.27)
				)
				(justify mirror)
			)
		)
		(property "Value" ""
			(at 0 0 0)
			(layer "B.Fab")
			(effects
				(font
					(size 1.27 1.27)
				)
				(justify mirror)
			)
		)
		(duplicate_pad_numbers_are_jumpers no)
		(fp_line
			(start -0.7874 -0.4064)
			(end -0.7874 0.4064)
			(stroke
				(width 0.1524)
				(type default)
			)
			(layer "B.SilkS")
		)
		(fp_line
			(start -0.7874 0.4064)
			(end 0.7874 0.4064)
			(stroke
				(width 0.1524)
				(type default)
			)
			(layer "B.SilkS")
		)
		(fp_line
			(start 0.7874 -0.4064)
			(end -0.7874 -0.4064)
			(stroke
				(width 0.1524)
				(type default)
			)
			(layer "B.SilkS")
		)
		(fp_line
			(start 0.7874 0.4064)
			(end 0.7874 -0.4064)
			(stroke
				(width 0.1524)
				(type default)
			)
			(layer "B.SilkS")
		)
		(fp_line
			(start -0.67945 -0.3048)
			(end -0.67945 0.3048)
			(stroke
				(width 0.1)
				(type default)
			)
			(layer "B.Fab")
		)
		(fp_line
			(start -0.67945 0.3048)
			(end -0.120396 0.3048)
			(stroke
				(width 0.1)
				(type default)
			)
			(layer "B.Fab")
		)
		(fp_line
			(start -0.12065 -0.3048)
			(end -0.67945 -0.3048)
			(stroke
				(width 0.1)
				(type default)
			)
			(layer "B.Fab")
		)
		(fp_line
			(start -0.12065 -0.2794)
			(end -0.12065 -0.3048)
			(stroke
				(width 0.1)
				(type default)
			)
			(layer "B.Fab")
		)
		(fp_line
			(start -0.120396 0.2794)
			(end 0.12065 0.2794)
			(stroke
				(width 0.1)
				(type default)
			)
			(layer "B.Fab")
		)
		(fp_line
			(start -0.120396 0.3048)
			(end -0.120396 0.2794)
			(stroke
				(width 0.1)
				(type default)
			)
			(layer "B.Fab")
		)
		(fp_line
			(start 0.12065 -0.305054)
			(end 0.12065 -0.2794)
			(stroke
				(width 0.1)
				(type default)
			)
			(layer "B.Fab")
		)
		(fp_line
			(start 0.12065 -0.2794)
			(end -0.12065 -0.2794)
			(stroke
				(width 0.1)
				(type default)
			)
			(layer "B.Fab")
		)
		(fp_line
			(start 0.12065 0.2794)
			(end 0.12065 0.3048)
			(stroke
				(width 0.1)
				(type default)
			)
			(layer "B.Fab")
		)
		(fp_line
			(start 0.12065 0.3048)
			(end 0.67945 0.3048)
			(stroke
				(width 0.1)
				(type default)
			)
			(layer "B.Fab")
		)
		(fp_line
			(start 0.67945 -0.305054)
			(end 0.12065 -0.305054)
			(stroke
				(width 0.1)
				(type default)
			)
			(layer "B.Fab")
		)
		(fp_line
			(start 0.67945 0.3048)
			(end 0.67945 -0.305054)
			(stroke
				(width 0.1)
				(type default)
			)
			(layer "B.Fab")
		)
		(pad "1" smd circle
			(at 0.40005 0 180)
			(size 0 0)
			(layers "B.Cu" "B.Mask" "B.Paste")
			(net "P1V8_STBY_AVDDPLL")
		)
		(pad "2" smd circle
			(at -0.40005 0 180)
			(size 0 0)
			(layers "B.Cu" "B.Mask" "B.Paste")
			(net "GND")
		)
	)
	(footprint ""
		(layer "B.Cu")
		(at 7.239 -61.087)
		(property "Reference" "C265"
			(at 0 0 0)
			(layer "B.SilkS")
			(hide yes)
			(effects
				(font
					(size 1.27 1.27)
				)
				(justify mirror)
			)
		)
		(property "Value" ""
			(at 0 0 0)
			(layer "B.Fab")
			(effects
				(font
					(size 1.27 1.27)
				)
				(justify mirror)
			)
		)
		(duplicate_pad_numbers_are_jumpers no)
		(fp_line
			(start -1.524 -0.762)
			(end -1.524 0.762)
			(stroke
				(width 0.1524)
				(type default)
			)
			(layer "B.SilkS")
		)
		(fp_line
			(start -1.524 0.762)
			(end 1.524 0.762)
			(stroke
				(width 0.1524)
				(type default)
			)
			(layer "B.SilkS")
		)
		(fp_line
			(start 1.524 -0.762)
			(end -1.524 -0.762)
			(stroke
				(width 0.1524)
				(type default)
			)
			(layer "B.SilkS")
		)
		(fp_line
			(start 1.524 0.762)
			(end 1.524 -0.762)
			(stroke
				(width 0.1524)
				(type default)
			)
			(layer "B.SilkS")
		)
		(fp_line
			(start -1.1049 -0.724916)
			(end 1.1049 -0.724916)
			(stroke
				(width 0.1)
				(type default)
			)
			(layer "B.Fab")
		)
		(fp_line
			(start -1.1049 0.724916)
			(end -1.1049 -0.724916)
			(stroke
				(width 0.1)
				(type default)
			)
			(layer "B.Fab")
		)
		(fp_line
			(start 1.1049 -0.724916)
			(end 1.1049 0.724916)
			(stroke
				(width 0.1)
				(type default)
			)
			(layer "B.Fab")
		)
		(fp_line
			(start 1.1049 0.724916)
			(end -1.1049 0.724916)
			(stroke
				(width 0.1)
				(type default)
			)
			(layer "B.Fab")
		)
		(pad "1" smd rect
			(at 0.889 0)
			(size 1.016 1.27)
			(layers "B.Cu" "B.Mask" "B.Paste")
			(net "SW_P3V3_AUX_FLT")
		)
		(pad "2" smd rect
			(at -0.889 0)
			(size 1.016 1.27)
			(layers "B.Cu" "B.Mask" "B.Paste")
			(net "GND")
		)
	)
	(footprint ""
		(layer "B.Cu")
		(at 46.502066 -21.26234 180)
		(property "Reference" "U23"
			(at -1.453134 -2.41681 0)
			(unlocked yes)
			(layer "B.SilkS")
			(effects
				(font
					(size 0.7874 0.5842)
					(thickness 0.1524)
				)
				(justify left mirror)
			)
		)
		(property "Value" ""
			(at 0 0 0)
			(layer "B.Fab")
			(effects
				(font
					(size 1.27 1.27)
				)
				(justify mirror)
			)
		)
		(duplicate_pad_numbers_are_jumpers no)
		(fp_line
			(start 1.733296 1.549908)
			(end -1.733296 1.549908)
			(stroke
				(width 0.1524)
				(type default)
			)
			(layer "B.SilkS")
		)
		(fp_line
			(start 1.733296 -1.549908)
			(end 1.733296 1.549908)
			(stroke
				(width 0.1524)
				(type default)
			)
			(layer "B.SilkS")
		)
		(fp_line
			(start 0.660908 -1.549908)
			(end 1.733296 -1.549908)
			(stroke
				(width 0.1524)
				(type default)
			)
			(layer "B.SilkS")
		)
		(fp_line
			(start 0 -0.889)
			(end 0.660908 -1.549908)
			(stroke
				(width 0.1524)
				(type default)
			)
			(layer "B.SilkS")
		)
		(fp_line
			(start -0.660908 -1.549908)
			(end 0 -0.889)
			(stroke
				(width 0.1524)
				(type default)
			)
			(layer "B.SilkS")
		)
		(fp_line
			(start -1.733296 1.549908)
			(end -1.733296 -1.549908)
			(stroke
				(width 0.1524)
				(type default)
			)
			(layer "B.SilkS")
		)
		(fp_line
			(start -1.733296 -1.549908)
			(end -0.660908 -1.549908)
			(stroke
				(width 0.1524)
				(type default)
			)
			(layer "B.SilkS")
		)
		(fp_poly
			(pts
				(xy 0.977646 -2.547874) (xy 1.485646 -2.547874) (xy 1.231646 -2.039874)
			)
			(stroke
				(width 0)
				(type default)
			)
			(fill yes)
			(layer "B.SilkS")
		)
		(fp_line
			(start 0.849884 1.549908)
			(end -0.849884 1.549908)
			(stroke
				(width 0.1)
				(type default)
			)
			(layer "B.Fab")
		)
		(fp_line
			(start 0.849884 -1.549908)
			(end 0.849884 1.549908)
			(stroke
				(width 0.1)
				(type default)
			)
			(layer "B.Fab")
		)
		(fp_line
			(start -0.849884 1.549908)
			(end -0.849884 -1.549908)
			(stroke
				(width 0.1)
				(type default)
			)
			(layer "B.Fab")
		)
		(fp_line
			(start -0.849884 -1.549908)
			(end 0.849884 -1.549908)
			(stroke
				(width 0.1)
				(type default)
			)
			(layer "B.Fab")
		)
		(fp_poly
			(pts
				(xy 2.4384 -1.20396) (xy 2.4384 -0.69596) (xy 1.9304 -0.94996)
			)
			(stroke
				(width 0)
				(type default)
			)
			(fill yes)
			(layer "B.Fab")
		)
		(pad "1" smd rect
			(at 1.199896 -0.94996 90)
			(size 0.5588 0.8128)
			(layers "B.Cu" "B.Mask" "B.Paste")
			(net "Net_245")
		)
		(pad "2" smd rect
			(at 1.199896 0 90)
			(size 0.5588 0.8128)
			(layers "B.Cu" "B.Mask" "B.Paste")
			(net "DEBUG_PORT_PRSNT")
		)
		(pad "3" smd rect
			(at 1.199896 0.94996 90)
			(size 0.5588 0.8128)
			(layers "B.Cu" "B.Mask" "B.Paste")
			(net "GND")
		)
		(pad "4" smd rect
			(at -1.199896 0.94996 90)
			(size 0.5588 0.8128)
			(layers "B.Cu" "B.Mask" "B.Paste")
			(net "DEBUG_PORT_PRSNT_BUF_R_EN")
		)
		(pad "5" smd rect
			(at -1.199896 -0.94996 90)
			(size 0.5588 0.8128)
			(layers "B.Cu" "B.Mask" "B.Paste")
			(net "P3V3_AUX")
		)
	)
	(footprint ""
		(layer "B.Cu")
		(at 55.499 -34.671 90)
		(property "Reference" "R583"
			(at 0 0 90)
			(layer "B.SilkS")
			(hide yes)
			(effects
				(font
					(size 1.27 1.27)
				)
				(justify mirror)
			)
		)
		(property "Value" ""
			(at 0 0 90)
			(layer "B.Fab")
			(effects
				(font
					(size 1.27 1.27)
				)
				(justify mirror)
			)
		)
		(duplicate_pad_numbers_are_jumpers no)
		(fp_line
			(start 0.7874 -0.4064)
			(end -0.7874 -0.4064)
			(stroke
				(width 0.1524)
				(type default)
			)
			(layer "B.SilkS")
		)
		(fp_line
			(start -0.7874 -0.4064)
			(end -0.7874 0.4064)
			(stroke
				(width 0.1524)
				(type default)
			)
			(layer "B.SilkS")
		)
		(fp_line
			(start 0.7874 0.4064)
			(end 0.7874 -0.4064)
			(stroke
				(width 0.1524)
				(type default)
			)
			(layer "B.SilkS")
		)
		(fp_line
			(start -0.7874 0.4064)
			(end 0.7874 0.4064)
			(stroke
				(width 0.1524)
				(type default)
			)
			(layer "B.SilkS")
		)
		(fp_line
			(start 0.67945 -0.305054)
			(end 0.12065 -0.305054)
			(stroke
				(width 0.1)
				(type default)
			)
			(layer "B.Fab")
		)
		(fp_line
			(start 0.12065 -0.305054)
			(end 0.12065 -0.2794)
			(stroke
				(width 0.1)
				(type default)
			)
			(layer "B.Fab")
		)
		(fp_line
			(start -0.12065 -0.3048)
			(end -0.67945 -0.3048)
			(stroke
				(width 0.1)
				(type default)
			)
			(layer "B.Fab")
		)
		(fp_line
			(start -0.67945 -0.3048)
			(end -0.67945 0.3048)
			(stroke
				(width 0.1)
				(type default)
			)
			(layer "B.Fab")
		)
		(fp_line
			(start 0.12065 -0.2794)
			(end -0.12065 -0.2794)
			(stroke
				(width 0.1)
				(type default)
			)
			(layer "B.Fab")
		)
		(fp_line
			(start -0.12065 -0.2794)
			(end -0.12065 -0.3048)
			(stroke
				(width 0.1)
				(type default)
			)
			(layer "B.Fab")
		)
		(fp_line
			(start 0.12065 0.2794)
			(end 0.12065 0.3048)
			(stroke
				(width 0.1)
				(type default)
			)
			(layer "B.Fab")
		)
		(fp_line
			(start -0.120396 0.2794)
			(end 0.12065 0.2794)
			(stroke
				(width 0.1)
				(type default)
			)
			(layer "B.Fab")
		)
		(fp_line
			(start 0.67945 0.3048)
			(end 0.67945 -0.305054)
			(stroke
				(width 0.1)
				(type default)
			)
			(layer "B.Fab")
		)
		(fp_line
			(start 0.12065 0.3048)
			(end 0.67945 0.3048)
			(stroke
				(width 0.1)
				(type default)
			)
			(layer "B.Fab")
		)
		(fp_line
			(start -0.120396 0.3048)
			(end -0.120396 0.2794)
			(stroke
				(width 0.1)
				(type default)
			)
			(layer "B.Fab")
		)
		(fp_line
			(start -0.67945 0.3048)
			(end -0.120396 0.3048)
			(stroke
				(width 0.1)
				(type default)
			)
			(layer "B.Fab")
		)
		(pad "1" smd circle
			(at 0.40005 0 270)
			(size 0 0)
			(layers "B.Cu" "B.Mask" "B.Paste")
			(net "SMB_BMC_MM10_R_SCL")
		)
		(pad "2" smd circle
			(at -0.40005 0 270)
			(size 0 0)
			(layers "B.Cu" "B.Mask" "B.Paste")
			(net "SMB_BMC_MM10_SCL")
		)
	)
	(footprint ""
		(layer "B.Cu")
		(at 114.554 4.572 -90)
		(property "Reference" "X19"
			(at 2.07137 1.4605 0)
			(unlocked yes)
			(layer "B.SilkS")
			(effects
				(font
					(size 0.7874 0.5842)
					(thickness 0.1524)
				)
				(justify left mirror)
			)
		)
		(property "Value" ""
			(at 0 0 90)
			(layer "B.Fab")
			(effects
				(font
					(size 1.27 1.27)
				)
				(justify mirror)
			)
		)
		(property "Device Type" "TP_TDR_4P_FTS_TH-TP_TDR_4P_DIPA"
			(at -1.30175 1.27 180)
			(unlocked yes)
			(layer "B.Fab")
			(hide yes)
			(effects
				(font
					(size 0.635 0.4064)
					(thickness 0.1524)
				)
				(justify mirror)
			)
		)
		(property "User Part Number" "N_A"
			(at -1.30175 1.27 180)
			(unlocked yes)
			(layer "Cmts.User")
			(hide yes)
			(effects
				(font
					(size 0.635 0.4064)
					(thickness 0.1524)
				)
				(justify mirror)
			)
		)
		(duplicate_pad_numbers_are_jumpers no)
		(fp_line
			(start -2.54 3.81)
			(end -2.54 3.6703)
			(stroke
				(width 0.1524)
				(type default)
			)
			(layer "B.SilkS")
		)
		(fp_line
			(start 0 3.81)
			(end -2.54 3.81)
			(stroke
				(width 0.1524)
				(type default)
			)
			(layer "B.SilkS")
		)
		(fp_line
			(start 0 3.175)
			(end 0 3.81)
			(stroke
				(width 0.1524)
				(type default)
			)
			(layer "B.SilkS")
		)
		(fp_line
			(start -2.54 1.4097)
			(end -2.54 1.1303)
			(stroke
				(width 0.1524)
				(type default)
			)
			(layer "B.SilkS")
		)
		(fp_line
			(start 0 0.635)
			(end 0 1.905)
			(stroke
				(width 0.1524)
				(type default)
			)
			(layer "B.SilkS")
		)
		(fp_line
			(start -2.54 -1.1303)
			(end -2.54 -1.27)
			(stroke
				(width 0.1524)
				(type default)
			)
			(layer "B.SilkS")
		)
		(fp_line
			(start -2.54 -1.27)
			(end 0 -1.27)
			(stroke
				(width 0.1524)
				(type default)
			)
			(layer "B.SilkS")
		)
		(fp_line
			(start 0 -1.27)
			(end 0 -0.635)
			(stroke
				(width 0.1524)
				(type default)
			)
			(layer "B.SilkS")
		)
		(fp_poly
			(pts
				(xy 0.761746 0) (xy 2.285746 -0.762) (xy 2.285746 0.762)
			)
			(stroke
				(width 0)
				(type default)
			)
			(fill yes)
			(layer "B.SilkS")
		)
		(fp_line
			(start -2.54 3.81)
			(end -2.54 -1.27)
			(stroke
				(width 0.1)
				(type default)
			)
			(layer "B.Fab")
		)
		(fp_line
			(start 0 3.81)
			(end -2.54 3.81)
			(stroke
				(width 0.1)
				(type default)
			)
			(layer "B.Fab")
		)
		(fp_line
			(start -2.54 -1.27)
			(end 0 -1.27)
			(stroke
				(width 0.1)
				(type default)
			)
			(layer "B.Fab")
		)
		(fp_line
			(start 0 -1.27)
			(end 0 3.81)
			(stroke
				(width 0.1)
				(type default)
			)
			(layer "B.Fab")
		)
		(fp_poly
			(pts
				(xy 0.761746 0) (xy 2.285746 -0.762) (xy 2.285746 0.762)
			)
			(stroke
				(width 0)
				(type default)
			)
			(fill yes)
			(layer "B.Fab")
		)
		(pad "1" thru_hole circle
			(at 0 0 90)
			(size 1.0033 1.0033)
			(drill 0.249936)
			(layers "*.Cu" "*.Mask")
			(remove_unused_layers no)
			(net "TDR_DIFF_100_TOP_DN")
			(clearance 0.10795)
			(padstack
				(mode front_inner_back)
				(layer "Inner"
					(shape circle)
					(size 0.8001 0.8001)
					(clearance 0.1524)
				)
				(layer "B.Cu"
					(shape circle)
					(size 1.0033 1.0033)
					(thermal_gap 0.10795)
					(clearance 0.10795)
				)
			)
		)
		(pad "2" thru_hole circle
			(at -2.54 0 90)
			(size 1.9939 1.9939)
			(drill 0.249936)
			(layers "*.Cu" "*.Mask")
			(remove_unused_layers no)
			(net "GND_P1")
			(clearance 0.10795)
			(padstack
				(mode front_inner_back)
				(layer "Inner"
					(shape circle)
					(size 0.8001 0.8001)
					(clearance 0.1524)
				)
				(layer "B.Cu"
					(shape circle)
					(size 1.9939 1.9939)
					(thermal_gap 0.10795)
					(clearance 0.10795)
				)
			)
		)
		(pad "3" thru_hole circle
			(at -2.54 2.54 90)
			(size 1.9939 1.9939)
			(drill 0.249936)
			(layers "*.Cu" "*.Mask")
			(remove_unused_layers no)
			(net "GND_P1")
			(clearance 0.10795)
			(padstack
				(mode front_inner_back)
				(layer "Inner"
					(shape circle)
					(size 0.8001 0.8001)
					(clearance 0.1524)
				)
				(layer "B.Cu"
					(shape circle)
					(size 1.9939 1.9939)
					(thermal_gap 0.10795)
					(clearance 0.10795)
				)
			)
		)
		(pad "4" thru_hole circle
			(at 0 2.54 90)
			(size 1.0033 1.0033)
			(drill 0.249936)
			(layers "*.Cu" "*.Mask")
			(remove_unused_layers no)
			(net "TDR_DIFF_100_TOP_DP")
			(clearance 0.10795)
			(padstack
				(mode front_inner_back)
				(layer "Inner"
					(shape circle)
					(size 0.8001 0.8001)
					(clearance 0.1524)
				)
				(layer "B.Cu"
					(shape circle)
					(size 1.0033 1.0033)
					(thermal_gap 0.10795)
					(clearance 0.10795)
				)
			)
		)
	)
	(footprint ""
		(layer "B.Cu")
		(at 43.367452 -30.816804 -90)
		(property "Reference" "R247"
			(at 0 0 90)
			(layer "B.SilkS")
			(hide yes)
			(effects
				(font
					(size 1.27 1.27)
				)
				(justify mirror)
			)
		)
		(property "Value" ""
			(at 0 0 90)
			(layer "B.Fab")
			(effects
				(font
					(size 1.27 1.27)
				)
				(justify mirror)
			)
		)
		(duplicate_pad_numbers_are_jumpers no)
		(fp_line
			(start -0.7874 0.4064)
			(end 0.7874 0.4064)
			(stroke
				(width 0.1524)
				(type default)
			)
			(layer "B.SilkS")
		)
		(fp_line
			(start 0.7874 0.4064)
			(end 0.7874 -0.4064)
			(stroke
				(width 0.1524)
				(type default)
			)
			(layer "B.SilkS")
		)
		(fp_line
			(start -0.7874 -0.4064)
			(end -0.7874 0.4064)
			(stroke
				(width 0.1524)
				(type default)
			)
			(layer "B.SilkS")
		)
		(fp_line
			(start 0.7874 -0.4064)
			(end -0.7874 -0.4064)
			(stroke
				(width 0.1524)
				(type default)
			)
			(layer "B.SilkS")
		)
		(fp_line
			(start -0.67945 0.3048)
			(end -0.120396 0.3048)
			(stroke
				(width 0.1)
				(type default)
			)
			(layer "B.Fab")
		)
		(fp_line
			(start -0.120396 0.3048)
			(end -0.120396 0.2794)
			(stroke
				(width 0.1)
				(type default)
			)
			(layer "B.Fab")
		)
		(fp_line
			(start 0.12065 0.3048)
			(end 0.67945 0.3048)
			(stroke
				(width 0.1)
				(type default)
			)
			(layer "B.Fab")
		)
		(fp_line
			(start 0.67945 0.3048)
			(end 0.67945 -0.305054)
			(stroke
				(width 0.1)
				(type default)
			)
			(layer "B.Fab")
		)
		(fp_line
			(start -0.120396 0.2794)
			(end 0.12065 0.2794)
			(stroke
				(width 0.1)
				(type default)
			)
			(layer "B.Fab")
		)
		(fp_line
			(start 0.12065 0.2794)
			(end 0.12065 0.3048)
			(stroke
				(width 0.1)
				(type default)
			)
			(layer "B.Fab")
		)
		(fp_line
			(start -0.12065 -0.2794)
			(end -0.12065 -0.3048)
			(stroke
				(width 0.1)
				(type default)
			)
			(layer "B.Fab")
		)
		(fp_line
			(start 0.12065 -0.2794)
			(end -0.12065 -0.2794)
			(stroke
				(width 0.1)
				(type default)
			)
			(layer "B.Fab")
		)
		(fp_line
			(start -0.67945 -0.3048)
			(end -0.67945 0.3048)
			(stroke
				(width 0.1)
				(type default)
			)
			(layer "B.Fab")
		)
		(fp_line
			(start -0.12065 -0.3048)
			(end -0.67945 -0.3048)
			(stroke
				(width 0.1)
				(type default)
			)
			(layer "B.Fab")
		)
		(fp_line
			(start 0.12065 -0.305054)
			(end 0.12065 -0.2794)
			(stroke
				(width 0.1)
				(type default)
			)
			(layer "B.Fab")
		)
		(fp_line
			(start 0.67945 -0.305054)
			(end 0.12065 -0.305054)
			(stroke
				(width 0.1)
				(type default)
			)
			(layer "B.Fab")
		)
		(pad "1" smd circle
			(at 0.40005 0 90)
			(size 0 0)
			(layers "B.Cu" "B.Mask" "B.Paste")
			(net "P3V3_AUX")
		)
		(pad "2" smd circle
			(at -0.40005 0 90)
			(size 0 0)
			(layers "B.Cu" "B.Mask" "B.Paste")
			(net "SMB_BMC_MM2_SDA")
		)
	)
)
